# T6G (Grand Teton) — schematic netlist excerpt (pin names and nets, part order shuffled) for the footprints in the layout excerpt that follows; sources: Cadence DE-HDL packaged netlist, KiCad conversion of 04192023_DAF0TMB3IC0_F0TG_MB_C_brd_V02_OCP.brd

J26  SCONN288_DDR506112002KQ  IO  pkg DDR288S_1-1VXC  page 99
  VIN_BULK0  = P12V_MEM_CPU1
  RFU0  = NC
  VIN_MGMT  = P3V3_AUX
  HSCL  = I3C_SPD_DDRB_CPU1_SCL
  HSDA  = I3C_SPD_DDRB_CPU1_SDA
  VSS0  = GND
  DQ0_A  = M_B_CPU1_SA_DQ<0>
  VSS1  = GND
  DQ1_A  = M_B_CPU1_SA_DQ<1>
  VSS2  = GND
  DQS0_A_T  = M_B_CPU1_SA_DQS_DP<0>
  DQS0_A_C  = M_B_CPU1_SA_DQS_DN<0>
  VSS3  = GND
  DQ4_A  = M_B_CPU1_SA_DQ<4>
  VSS4  = GND
  DQ5_A  = M_B_CPU1_SA_DQ<5>
  VSS5  = GND
  DQ8_A  = M_B_CPU1_SA_DQ<8>
  VSS6  = GND
  DQ9_A  = M_B_CPU1_SA_DQ<9>
  VSS7  = GND
  DQS1_A_T  = M_B_CPU1_SA_DQS_DP<1>
  DQS1_A_C  = M_B_CPU1_SA_DQS_DN<1>
  VSS8  = GND
  DQ12_A  = M_B_CPU1_SA_DQ<12>
  VSS9  = GND
  DQ13_A  = M_B_CPU1_SA_DQ<13>
  VSS10  = GND
  DQ16_A  = M_B_CPU1_SA_DQ<16>
  VSS11  = GND
  DQ17_A  = M_B_CPU1_SA_DQ<17>
  VSS12  = GND
  DQS2_A_T  = M_B_CPU1_SA_DQS_DP<2>
  DQS2_A_C  = M_B_CPU1_SA_DQS_DN<2>
  VSS13  = GND
  DQ20_A  = M_B_CPU1_SA_DQ<20>
  VSS14  = GND
  DQ21_A  = M_B_CPU1_SA_DQ<21>
  VSS15  = GND
  DQ24_A  = M_B_CPU1_SA_DQ<24>
  VSS16  = GND
  DQ25_A  = M_B_CPU1_SA_DQ<25>
  VSS17  = GND
  DQS3_A_T  = M_B_CPU1_SA_DQS_DP<3>
  DQS3_A_C  = M_B_CPU1_SA_DQS_DN<3>
  VSS18  = GND
  DQ28_A  = M_B_CPU1_SA_DQ<28>
  VSS19  = GND
  DQ29_A  = M_B_CPU1_SA_DQ<29>
  VSS20  = GND
  CB0_A  = M_B_CPU1_SA_CB<0>
  VSS21  = GND
  CB1_A  = M_B_CPU1_SA_CB<1>
  VSS22  = GND
  DQS4_A_T  = M_B_CPU1_SA_DQS_DP<4>
  DQS4_A_C  = M_B_CPU1_SA_DQS_DN<4>
  VSS23  = GND
  CB4_A  = M_B_CPU1_SA_CB<4>
  VSS24  = GND
  CB5_A  = M_B_CPU1_SA_CB<5>
  VSS25  = GND
  ALERT_N  = M_B_CPU1_ALERT_N
  VSS26  = GND
  CS0_A_N  = M_B_CPU1_SA_CS_N<0>
  VSS27  = GND
  CA0_A  = M_B_CPU1_SA_CA<0>
  VSS28  = GND
  CA2_A  = M_B_CPU1_SA_CA<2>
  VSS29  = GND
  CA4_A  = M_B_CPU1_SA_CA<4>
  VSS30  = GND
  CA6_A  = M_B_CPU1_SA_CA<6>
  VSS31  = GND
  PAR_A  = M_B_CPU1_SA_PAR
  VSS32  = GND
  CA0_B  = M_B_CPU1_SB_CA<0>
  VSS33  = GND
  CA2_B  = M_B_CPU1_SB_CA<2>
  VSS34  = GND
  CA4_B  = M_B_CPU1_SB_CA<4>
  VSS35  = GND
  CA6_B  = M_B_CPU1_SB_CA<6>
  VSS36  = GND
  CS0_B_N  = M_B_CPU1_SB_CS_N<0>
  VSS37  = GND
  \lbd||rsp_a_n\  = M_B_CPU1_SA_RSP<0>
  \lbs||rsp_b_n\  = M_B_CPU1_SB_RSP<0>
  VSS38  = GND
  CB4_B  = M_B_CPU1_SB_CB<4>
  VSS39  = GND
  CB5_B  = M_B_CPU1_SB_CB<5>
  VSS40  = GND
  \dqs9_b_t||tdqs9_b_t||dbi4_b_n\  = M_B_CPU1_SB_DQS_DP<9>
  \dqs9_b_c||tdqs9_b_c\  = M_B_CPU1_SB_DQS_DN<9>
  VSS41  = GND
  CB0_B  = M_B_CPU1_SB_CB<0>
  VSS42  = GND
  CB1_B  = M_B_CPU1_SB_CB<1>
  VSS43  = GND
  DQ0_B  = M_B_CPU1_SB_DQ<0>
  VSS44  = GND
  DQ1_B  = M_B_CPU1_SB_DQ<1>
  VSS45  = GND
  DQS0_B_T  = M_B_CPU1_SB_DQS_DP<0>
  DQS0_B_C  = M_B_CPU1_SB_DQS_DN<0>
  VSS46  = GND
  DQ4_B  = M_B_CPU1_SB_DQ<4>
  VSS47  = GND
  DQ5_B  = M_B_CPU1_SB_DQ<5>
  VSS48  = GND
  DQ8_B  = M_B_CPU1_SB_DQ<8>
  VSS49  = GND
  DQ9_B  = M_B_CPU1_SB_DQ<9>
  VSS50  = GND
  DQS1_B_T  = M_B_CPU1_SB_DQS_DP<1>
  DQS1_B_C  = M_B_CPU1_SB_DQS_DN<1>
  VSS51  = GND
  DQ12_B  = M_B_CPU1_SB_DQ<12>
  VSS52  = GND
  DQ13_B  = M_B_CPU1_SB_DQ<13>
  VSS53  = GND
  DQ16_B  = M_B_CPU1_SB_DQ<16>
  VSS54  = GND
  DQ17_B  = M_B_CPU1_SB_DQ<17>
  VSS55  = GND
  DQS2_B_T  = M_B_CPU1_SB_DQS_DP<2>
  DQS2_B_C  = M_B_CPU1_SB_DQS_DN<2>
  VSS56  = GND
  DQ20_B  = M_B_CPU1_SB_DQ<20>
  VSS57  = GND
  DQ21_B  = M_B_CPU1_SB_DQ<21>
  VSS58  = GND
  DQ24_B  = M_B_CPU1_SB_DQ<24>
  VSS59  = GND
  DQ25_B  = M_B_CPU1_SB_DQ<25>
  VSS60  = GND
  DQS3_B_T  = M_B_CPU1_SB_DQS_DP<3>
  DQS3_B_C  = M_B_CPU1_SB_DQS_DN<3>
  VSS61  = GND
  DQ28_B  = M_B_CPU1_SB_DQ<28>
  VSS62  = GND
  DQ29_B  = M_B_CPU1_SB_DQ<29>
  VSS63  = GND
  RFU1  = NC
  VIN_BULK1  = P12V_MEM_CPU1
  VIN_BULK2  = P12V_MEM_CPU1
  \pwr_good||fail_n\  = PWRGD_CHB_CPU1_DIMM
  HAS  = PD_CHB_CPU1_DIMM_SAA
  RFU2  = NC
  RFU3  = NC
  VSS64  = GND
  DQ2_A  = M_B_CPU1_SA_DQ<2>
  VSS65  = GND
  DQ3_A  = M_B_CPU1_SA_DQ<3>
  VSS66  = GND
  \dqs5_a_c||tdqs5_a_c||dqs5_a_t||tdqs5_a_t\  = M_B_CPU1_SA_DQS_DN<5>
  \dqs5_a_t||tdqs5_a_t\  = M_B_CPU1_SA_DQS_DP<5>
  VSS67  = GND
  DQ6_A  = M_B_CPU1_SA_DQ<6>
  VSS68  = GND
  DQ7_A  = M_B_CPU1_SA_DQ<7>
  VSS69  = GND
  DQ10_A  = M_B_CPU1_SA_DQ<10>
  VSS70  = GND
  DQ11_A  = M_B_CPU1_SA_DQ<11>
  VSS71  = GND
  \dqs6_a_c||tdqs6_a_c||dqs6_a_t||tdqs6_a_t\  = M_B_CPU1_SA_DQS_DN<6>
  \dqs6_a_t||tdqs6_a_t\  = M_B_CPU1_SA_DQS_DP<6>
  VSS72  = GND
  DQ14_A  = M_B_CPU1_SA_DQ<14>
  VSS73  = GND
  DQ15_A  = M_B_CPU1_SA_DQ<15>
  VSS74  = GND
  DQ18_A  = M_B_CPU1_SA_DQ<18>
  VSS75  = GND
  DQ19_A  = M_B_CPU1_SA_DQ<19>
  VSS76  = GND
  \dqs7_a_c||tdqs7_a_c\  = M_B_CPU1_SA_DQS_DN<7>
  \dqs7_a_t||tdqs7_a_t\  = M_B_CPU1_SA_DQS_DP<7>
  VSS77  = GND
  DQ22_A  = M_B_CPU1_SA_DQ<22>
  VSS78  = GND
  DQ23_A  = M_B_CPU1_SA_DQ<23>
  VSS79  = GND
  DQ26_A  = M_B_CPU1_SA_DQ<26>
  VSS80  = GND
  DQ27_A  = M_B_CPU1_SA_DQ<27>
  VSS81  = GND
  \dqs8_a_c||tdqs8_a_c\  = M_B_CPU1_SA_DQS_DN<8>
  \dqs8_a_t||tdqs8_a_t\  = M_B_CPU1_SA_DQS_DP<8>
  VSS82  = GND
  DQ30_A  = M_B_CPU1_SA_DQ<30>
  VSS83  = GND
  DQ31_A  = M_B_CPU1_SA_DQ<31>
  VSS84  = GND
  CB2_A  = M_B_CPU1_SA_CB<2>
  VSS85  = GND
  CB3_A  = M_B_CPU1_SA_CB<3>
  VSS86  = GND
  \dqs9_a_c||tdqs9_a_c\  = M_B_CPU1_SA_DQS_DN<9>
  \dqs9_a_t||tdqs9_a_t\  = M_B_CPU1_SA_DQS_DP<9>
  VSS87  = GND
  CB6_A  = M_B_CPU1_SA_CB<6>
  VSS88  = GND
  CB7_A  = M_B_CPU1_SA_CB<7>
  VSS89  = GND
  RESET_N  = M_B_CPU1_RESET_N
  VSS90  = GND
  CS1_A_N  = M_B_CPU1_SA_CS_N<1>
  VSS91  = GND
  CA1_A  = M_B_CPU1_SA_CA<1>
  VSS92  = GND
  CA3_A  = M_B_CPU1_SA_CA<3>
  VSS93  = GND
  CA5_A  = M_B_CPU1_SA_CA<5>
  VSS94  = GND
  CK_T  = M_B_CPU1_CLK_DP<0>
  CK_C  = M_B_CPU1_CLK_DN<0>
  VSS95  = GND
  RFU4  = NC
  CA1_B  = M_B_CPU1_SB_CA<1>
  VSS96  = GND
  CA3_B  = M_B_CPU1_SB_CA<3>
  VSS97  = GND
  CA5_B  = M_B_CPU1_SB_CA<5>
  VSS98  = GND
  PAR_B  = M_B_CPU1_SB_PAR
  VSS99  = GND
  CS1_B_N  = M_B_CPU1_SB_CS_N<1>
  VSS100  = GND
  RFU5  = NC
  RFU6  = NC
  VSS101  = GND
  CB6_B  = M_B_CPU1_SB_CB<6>
  VSS102  = GND
  CB7_B  = M_B_CPU1_SB_CB<7>
  VSS103  = GND
  DQS4_B_C  = M_B_CPU1_SB_DQS_DN<4>
  DQS4_B_T  = M_B_CPU1_SB_DQS_DP<4>
  VSS104  = GND
  CB2_B  = M_B_CPU1_SB_CB<2>
  VSS105  = GND
  CB3_B  = M_B_CPU1_SB_CB<3>
  VSS106  = GND
  DQ2_B  = M_B_CPU1_SB_DQ<2>
  VSS107  = GND
  DQ3_B  = M_B_CPU1_SB_DQ<3>
  VSS108  = GND
  \dqs5_b_c||tdqs5_b_c\  = M_B_CPU1_SB_DQS_DN<5>
  \dqs5_b_t||tdqs5_b_t\  = M_B_CPU1_SB_DQS_DP<5>
  VSS109  = GND
  DQ6_B  = M_B_CPU1_SB_DQ<6>
  VSS110  = GND
  DQ7_B  = M_B_CPU1_SB_DQ<7>
  VSS111  = GND
  DQ10_B  = M_B_CPU1_SB_DQ<10>
  VSS112  = GND
  DQ11_B  = M_B_CPU1_SB_DQ<11>
  VSS113  = GND
  \dqs6_b_c||tdqs6_b_c\  = M_B_CPU1_SB_DQS_DN<6>
  \dqs6_b_t||tdqs6_b_t\  = M_B_CPU1_SB_DQS_DP<6>
  VSS114  = GND
  DQ14_B  = M_B_CPU1_SB_DQ<14>
  VSS115  = GND
  DQ15_B  = M_B_CPU1_SB_DQ<15>
  VSS116  = GND
  DQ18_B  = M_B_CPU1_SB_DQ<18>
  VSS117  = GND
  DQ19_B  = M_B_CPU1_SB_DQ<19>
  VSS118  = GND
  \dqs7_b_c||tdqs7_b_c\  = M_B_CPU1_SB_DQS_DN<7>
  \dqs7_b_t||tdqs7_b_t\  = M_B_CPU1_SB_DQS_DP<7>
  VSS119  = GND
  DQ22_B  = M_B_CPU1_SB_DQ<22>
  VSS120  = GND
  DQ23_B  = M_B_CPU1_SB_DQ<23>
  VSS121  = GND
  DQ26_B  = M_B_CPU1_SB_DQ<26>
  VSS122  = GND
  DQ27_B  = M_B_CPU1_SB_DQ<27>
  VSS123  = GND
  \dqs8_b_c||tdqs8_b_c\  = M_B_CPU1_SB_DQS_DN<8>
  \dqs8_b_t||tdqs8_b_t\  = M_B_CPU1_SB_DQS_DP<8>
  VSS124  = GND
  DQ30_B  = M_B_CPU1_SB_DQ<30>
  VSS125  = GND
  DQ31_B  = M_B_CPU1_SB_DQ<31>
  VSS126  = GND
  G1  = GND
  G2  = GND
  G3  = GND

(kicad_pcb
	(version 20260206)
	(generator "pcbnew")
	(generator_version "10.0")
	(general
		(thickness 1.6)
		(legacy_teardrops no)
	)
	(paper "A4")
	(title_block
		(title "04192023_DAF0TMB3IC0_F0TG_MB_C_brd_V02_OCP.brd")
		(comment 1 "Grand Teton / footprint 4371 of 8354 (J26), pads 1-46 of 291")
	)
	(layers
		(0 "F.Cu" signal "TOP")
		(4 "In1.Cu" signal "GND")
		(6 "In2.Cu" signal "IN1")
		(8 "In3.Cu" signal "GND1")
		(10 "In4.Cu" signal "IN2")
		(12 "In5.Cu" signal "GND2")
		(14 "In6.Cu" signal "IN3")
		(16 "In7.Cu" signal "GND3")
		(18 "In8.Cu" signal "VCC")
		(20 "In9.Cu" signal "VCC1")
		(22 "In10.Cu" signal "GND4")
		(24 "In11.Cu" signal "IN4")
		(26 "In12.Cu" signal "GND5")
		(28 "In13.Cu" signal "IN5")
		(30 "In14.Cu" signal "GND6")
		(32 "In15.Cu" signal "IN6")
		(34 "In16.Cu" signal "GND7")
		(2 "B.Cu" signal "BOTTOM")
		(9 "F.Adhes" user "F.Adhesive")
		(11 "B.Adhes" user "B.Adhesive")
		(13 "F.Paste" user "Package Geometry/Pastemask Top")
		(15 "B.Paste" user "Package Geometry/Pastemask Bottom")
		(5 "F.SilkS" user "Ref Des/Silkscreen Top")
		(7 "B.SilkS" user "Ref Des/Silkscreen Bottom")
		(1 "F.Mask" user "Board Geometry/Soldermask Top")
		(3 "B.Mask" user "Board Geometry/Soldermask Bottom")
		(17 "Dwgs.User" user "User.Drawings")
		(19 "Cmts.User" user "User.Comments")
		(21 "Eco1.User" user "User.Eco1")
		(23 "Eco2.User" user "User.Eco2")
		(25 "Edge.Cuts" user "Board Geometry/Outline")
		(27 "Margin" user)
		(31 "F.CrtYd" user "Package Geometry/Place Bound Top")
		(29 "B.CrtYd" user "Package Geometry/Place Bound Bottom")
		(35 "F.Fab" user "Ref Des/Assembly Top")
		(33 "B.Fab" user "Ref Des/Assembly Bottom")
	)
	(footprint ""
		(layer "F.Cu")
		(at 49.834038 -255.560322 180)
		(property "Reference" "J26"
			(at -0.703326 -82.357722 0)
			(unlocked yes)
			(layer "F.SilkS")
			(effects
				(font
					(size 0.7874 0.5842)
					(thickness 0.1524)
				)
			)
		)
		(property "Value" ""
			(at 0 0 180)
			(layer "F.Fab")
			(effects
				(font
					(size 1.27 1.27)
				)
			)
		)
		(duplicate_pad_numbers_are_jumpers no)
		(pad "1" smd rect
			(at -2.050034 -63.324994 90)
			(size 0.519938 1.4986)
			(layers "F.Cu" "F.Mask" "F.Paste")
			(net "P12V_MEM_CPU1")
		)
		(pad "2" smd rect
			(at -2.050034 -62.47511 90)
			(size 0.519938 1.4986)
			(layers "F.Cu" "F.Mask" "F.Paste")
			(net "Net_2270")
		)
		(pad "3" smd rect
			(at -2.050034 -61.624972 90)
			(size 0.519938 1.4986)
			(layers "F.Cu" "F.Mask" "F.Paste")
			(net "P3V3_AUX")
		)
		(pad "4" smd rect
			(at -2.050034 -60.775088 90)
			(size 0.519938 1.4986)
			(layers "F.Cu" "F.Mask" "F.Paste")
			(net "I3C_SPD_DDRB_CPU1_SCL")
		)
		(pad "5" smd rect
			(at -2.050034 -59.92495 90)
			(size 0.519938 1.4986)
			(layers "F.Cu" "F.Mask" "F.Paste")
			(net "I3C_SPD_DDRB_CPU1_SDA")
		)
		(pad "6" smd rect
			(at -2.050034 -59.075066 90)
			(size 0.519938 1.4986)
			(layers "F.Cu" "F.Mask" "F.Paste")
			(net "GND")
		)
		(pad "7" smd rect
			(at -2.050034 -58.224928 90)
			(size 0.519938 1.4986)
			(layers "F.Cu" "F.Mask" "F.Paste")
			(net "M_B_CPU1_SA_DQ<0>")
		)
		(pad "8" smd rect
			(at -2.050034 -57.375044 90)
			(size 0.519938 1.4986)
			(layers "F.Cu" "F.Mask" "F.Paste")
			(net "GND")
		)
		(pad "9" smd rect
			(at -2.050034 -56.524906 90)
			(size 0.519938 1.4986)
			(layers "F.Cu" "F.Mask" "F.Paste")
			(net "M_B_CPU1_SA_DQ<1>")
		)
		(pad "10" smd rect
			(at -2.050034 -55.675022 90)
			(size 0.519938 1.4986)
			(layers "F.Cu" "F.Mask" "F.Paste")
			(net "GND")
		)
		(pad "11" smd rect
			(at -2.050034 -54.824884 90)
			(size 0.519938 1.4986)
			(layers "F.Cu" "F.Mask" "F.Paste")
			(net "M_B_CPU1_SA_DQS_DP<0>")
		)
		(pad "12" smd rect
			(at -2.050034 -53.975 90)
			(size 0.519938 1.4986)
			(layers "F.Cu" "F.Mask" "F.Paste")
			(net "M_B_CPU1_SA_DQS_DN<0>")
		)
		(pad "13" smd rect
			(at -2.050034 -53.125116 90)
			(size 0.519938 1.4986)
			(layers "F.Cu" "F.Mask" "F.Paste")
			(net "GND")
		)
		(pad "14" smd rect
			(at -2.050034 -52.274978 90)
			(size 0.519938 1.4986)
			(layers "F.Cu" "F.Mask" "F.Paste")
			(net "M_B_CPU1_SA_DQ<4>")
		)
		(pad "15" smd rect
			(at -2.050034 -51.425094 90)
			(size 0.519938 1.4986)
			(layers "F.Cu" "F.Mask" "F.Paste")
			(net "GND")
		)
		(pad "16" smd rect
			(at -2.050034 -50.574956 90)
			(size 0.519938 1.4986)
			(layers "F.Cu" "F.Mask" "F.Paste")
			(net "M_B_CPU1_SA_DQ<5>")
		)
		(pad "17" smd rect
			(at -2.050034 -49.725072 90)
			(size 0.519938 1.4986)
			(layers "F.Cu" "F.Mask" "F.Paste")
			(net "GND")
		)
		(pad "18" smd rect
			(at -2.050034 -48.874934 90)
			(size 0.519938 1.4986)
			(layers "F.Cu" "F.Mask" "F.Paste")
			(net "M_B_CPU1_SA_DQ<8>")
		)
		(pad "19" smd rect
			(at -2.050034 -48.02505 90)
			(size 0.519938 1.4986)
			(layers "F.Cu" "F.Mask" "F.Paste")
			(net "GND")
		)
		(pad "20" smd rect
			(at -2.050034 -47.174912 90)
			(size 0.519938 1.4986)
			(layers "F.Cu" "F.Mask" "F.Paste")
			(net "M_B_CPU1_SA_DQ<9>")
		)
		(pad "21" smd rect
			(at -2.050034 -46.325028 90)
			(size 0.519938 1.4986)
			(layers "F.Cu" "F.Mask" "F.Paste")
			(net "GND")
		)
		(pad "22" smd rect
			(at -2.050034 -45.47489 90)
			(size 0.519938 1.4986)
			(layers "F.Cu" "F.Mask" "F.Paste")
			(net "M_B_CPU1_SA_DQS_DP<1>")
		)
		(pad "23" smd rect
			(at -2.050034 -44.625006 90)
			(size 0.519938 1.4986)
			(layers "F.Cu" "F.Mask" "F.Paste")
			(net "M_B_CPU1_SA_DQS_DN<1>")
		)
		(pad "24" smd rect
			(at -2.050034 -43.775122 90)
			(size 0.519938 1.4986)
			(layers "F.Cu" "F.Mask" "F.Paste")
			(net "GND")
		)
		(pad "25" smd rect
			(at -2.050034 -42.924984 90)
			(size 0.519938 1.4986)
			(layers "F.Cu" "F.Mask" "F.Paste")
			(net "M_B_CPU1_SA_DQ<12>")
		)
		(pad "26" smd rect
			(at -2.050034 -42.0751 90)
			(size 0.519938 1.4986)
			(layers "F.Cu" "F.Mask" "F.Paste")
			(net "GND")
		)
		(pad "27" smd rect
			(at -2.050034 -41.224962 90)
			(size 0.519938 1.4986)
			(layers "F.Cu" "F.Mask" "F.Paste")
			(net "M_B_CPU1_SA_DQ<13>")
		)
		(pad "28" smd rect
			(at -2.050034 -40.375078 90)
			(size 0.519938 1.4986)
			(layers "F.Cu" "F.Mask" "F.Paste")
			(net "GND")
		)
		(pad "29" smd rect
			(at -2.050034 -39.52494 90)
			(size 0.519938 1.4986)
			(layers "F.Cu" "F.Mask" "F.Paste")
			(net "M_B_CPU1_SA_DQ<16>")
		)
		(pad "30" smd rect
			(at -2.050034 -38.675056 90)
			(size 0.519938 1.4986)
			(layers "F.Cu" "F.Mask" "F.Paste")
			(net "GND")
		)
		(pad "31" smd rect
			(at -2.050034 -37.824918 90)
			(size 0.519938 1.4986)
			(layers "F.Cu" "F.Mask" "F.Paste")
			(net "M_B_CPU1_SA_DQ<17>")
		)
		(pad "32" smd rect
			(at -2.050034 -36.975034 90)
			(size 0.519938 1.4986)
			(layers "F.Cu" "F.Mask" "F.Paste")
			(net "GND")
		)
		(pad "33" smd rect
			(at -2.050034 -36.124896 90)
			(size 0.519938 1.4986)
			(layers "F.Cu" "F.Mask" "F.Paste")
			(net "M_B_CPU1_SA_DQS_DP<2>")
		)
		(pad "34" smd rect
			(at -2.050034 -35.275012 90)
			(size 0.519938 1.4986)
			(layers "F.Cu" "F.Mask" "F.Paste")
			(net "M_B_CPU1_SA_DQS_DN<2>")
		)
		(pad "35" smd rect
			(at -2.050034 -34.425128 90)
			(size 0.519938 1.4986)
			(layers "F.Cu" "F.Mask" "F.Paste")
			(net "GND")
		)
		(pad "36" smd rect
			(at -2.050034 -33.57499 90)
			(size 0.519938 1.4986)
			(layers "F.Cu" "F.Mask" "F.Paste")
			(net "M_B_CPU1_SA_DQ<20>")
		)
		(pad "37" smd rect
			(at -2.050034 -32.725106 90)
			(size 0.519938 1.4986)
			(layers "F.Cu" "F.Mask" "F.Paste")
			(net "GND")
		)
		(pad "38" smd rect
			(at -2.050034 -31.874968 90)
			(size 0.519938 1.4986)
			(layers "F.Cu" "F.Mask" "F.Paste")
			(net "M_B_CPU1_SA_DQ<21>")
		)
		(pad "39" smd rect
			(at -2.050034 -31.025084 90)
			(size 0.519938 1.4986)
			(layers "F.Cu" "F.Mask" "F.Paste")
			(net "GND")
		)
		(pad "40" smd rect
			(at -2.050034 -30.174946 90)
			(size 0.519938 1.4986)
			(layers "F.Cu" "F.Mask" "F.Paste")
			(net "M_B_CPU1_SA_DQ<24>")
		)
		(pad "41" smd rect
			(at -2.050034 -29.325062 90)
			(size 0.519938 1.4986)
			(layers "F.Cu" "F.Mask" "F.Paste")
			(net "GND")
		)
		(pad "42" smd rect
			(at -2.050034 -28.474924 90)
			(size 0.519938 1.4986)
			(layers "F.Cu" "F.Mask" "F.Paste")
			(net "M_B_CPU1_SA_DQ<25>")
		)
		(pad "43" smd rect
			(at -2.050034 -27.62504 90)
			(size 0.519938 1.4986)
			(layers "F.Cu" "F.Mask" "F.Paste")
			(net "GND")
		)
		(pad "44" smd rect
			(at -2.050034 -26.774902 90)
			(size 0.519938 1.4986)
			(layers "F.Cu" "F.Mask" "F.Paste")
			(net "M_B_CPU1_SA_DQS_DP<3>")
		)
		(pad "45" smd rect
			(at -2.050034 -25.925018 90)
			(size 0.519938 1.4986)
			(layers "F.Cu" "F.Mask" "F.Paste")
			(net "M_B_CPU1_SA_DQS_DN<3>")
		)
		(pad "46" smd rect
			(at -2.050034 -25.07488 90)
			(size 0.519938 1.4986)
			(layers "F.Cu" "F.Mask" "F.Paste")
			(net "GND")
		)
	)
)
